G04 #@! TF.GenerationSoftware,KiCad,Pcbnew,(5.0.1)-3*
G04 #@! TF.CreationDate,2019-04-10T15:36:06+02:00*
G04 #@! TF.ProjectId,discovery,646973636F766572792E6B696361645F,rev?*
G04 #@! TF.SameCoordinates,PX4c4640PY8a48028*
G04 #@! TF.FileFunction,Other,Fab,Bot*
%FSLAX46Y46*%
G04 Gerber Fmt 4.6, Leading zero omitted, Abs format (unit mm)*
%MOMM*%
%LPD*%
G01*
G04 APERTURE LIST*
G04 APERTURE END LIST*
M02*
